# S9S_MB_2U (Grand Teton) — schematic netlist excerpt (pin names and nets, part order shuffled) for the footprints in the layout excerpt that follows; sources: Cadence DE-HDL packaged netlist, KiCad conversion of 03242023_DA0F0TMBIJ0_F0T_Motherboard_J_brd_V01_OCP.brd

C806  Q_CAP_DIFFBUS  DIFF BUS_0.22UF 6.3V 20% X6S  pkg C0201  page 175 : \1\ = P5E_CPU1_PE1_TX_C_DN<15> ; \2\ = P5E_CPU1_PE1_TX_DN<15>

Q137  MOSFET_NCH_DUAL  PJT138K IC  pkg SOT363XD  page 145
  S1  = GND
  G1  = GPU_3V3IO_RSVD3
  D2  = GPU_3V3IO_RSVD3_ISO
  S2  = GND
  G2  = GPU_3V3IO_RSVD3_N
  D1  = GPU_3V3IO_RSVD3_N

PC414  Q_CAPP  560UF 2.5V 20% OSCON  pkg THLF  page 289 : A = PVCCFA_EHV_FIVRA_CPU1 ; B = GND

(kicad_pcb
	(version 20260206)
	(generator "pcbnew")
	(generator_version "10.0")
	(general
		(thickness 1.6)
		(legacy_teardrops no)
	)
	(paper "A4")
	(title_block
		(title "03242023_DA0F0TMBIJ0_F0T_Motherboard_J_brd_V01_OCP.brd")
		(comment 1 "Grand Teton / footprints 2990-2992 of 6105")
	)
	(layers
		(0 "F.Cu" signal "TOP")
		(4 "In1.Cu" signal "GND")
		(6 "In2.Cu" signal "IN1")
		(8 "In3.Cu" signal "GND1")
		(10 "In4.Cu" signal "IN2")
		(12 "In5.Cu" signal "GND2")
		(14 "In6.Cu" signal "IN3")
		(16 "In7.Cu" signal "GND3")
		(18 "In8.Cu" signal "VCC")
		(20 "In9.Cu" signal "VCC1")
		(22 "In10.Cu" signal "GND4")
		(24 "In11.Cu" signal "IN4")
		(26 "In12.Cu" signal "GND5")
		(28 "In13.Cu" signal "IN5")
		(30 "In14.Cu" signal "GND6")
		(32 "In15.Cu" signal "IN6")
		(34 "In16.Cu" signal "GND7")
		(2 "B.Cu" signal "BOTTOM")
		(9 "F.Adhes" user "F.Adhesive")
		(11 "B.Adhes" user "B.Adhesive")
		(13 "F.Paste" user "Package Geometry/Pastemask Top")
		(15 "B.Paste" user "Package Geometry/Pastemask Bottom")
		(5 "F.SilkS" user "Ref Des/Silkscreen Top")
		(7 "B.SilkS" user "Ref Des/Silkscreen Bottom")
		(1 "F.Mask" user "Board Geometry/Soldermask Top")
		(3 "B.Mask" user "Board Geometry/Soldermask Bottom")
		(17 "Dwgs.User" user "User.Drawings")
		(19 "Cmts.User" user "User.Comments")
		(21 "Eco1.User" user "User.Eco1")
		(23 "Eco2.User" user "User.Eco2")
		(25 "Edge.Cuts" user "Board Geometry/Outline")
		(27 "Margin" user)
		(31 "F.CrtYd" user "Package Geometry/Place Bound Top")
		(29 "B.CrtYd" user "Package Geometry/Place Bound Bottom")
		(35 "F.Fab" user "Ref Des/Assembly Top")
		(33 "B.Fab" user "Ref Des/Assembly Bottom")
	)
	(footprint ""
		(layer "F.Cu")
		(at 364.940342 -390.48817)
		(property "Reference" "Q137"
			(at 2.02692 0.708152 0)
			(unlocked yes)
			(layer "F.SilkS")
			(effects
				(font
					(size 0.7874 0.5842)
					(thickness 0.1524)
				)
				(justify left)
			)
		)
		(property "Value" ""
			(at 0 0 0)
			(layer "F.Fab")
			(effects
				(font
					(size 1.27 1.27)
				)
			)
		)
		(duplicate_pad_numbers_are_jumpers no)
		(fp_line
			(start -1.332738 -1.100074)
			(end -0.4826 -1.100074)
			(stroke
				(width 0.1524)
				(type default)
			)
			(layer "F.SilkS")
		)
		(fp_line
			(start -1.332738 1.100074)
			(end -1.332738 -1.100074)
			(stroke
				(width 0.1524)
				(type default)
			)
			(layer "F.SilkS")
		)
		(fp_line
			(start -0.4826 -1.100074)
			(end 0 -0.541274)
			(stroke
				(width 0.1524)
				(type default)
			)
			(layer "F.SilkS")
		)
		(fp_line
			(start 0 -0.541274)
			(end 0.4826 -1.100074)
			(stroke
				(width 0.1524)
				(type default)
			)
			(layer "F.SilkS")
		)
		(fp_line
			(start 0.4826 -1.100074)
			(end 1.332738 -1.100074)
			(stroke
				(width 0.1524)
				(type default)
			)
			(layer "F.SilkS")
		)
		(fp_line
			(start 1.332738 -1.100074)
			(end 1.332738 1.100074)
			(stroke
				(width 0.1524)
				(type default)
			)
			(layer "F.SilkS")
		)
		(fp_line
			(start 1.332738 1.100074)
			(end -1.332738 1.100074)
			(stroke
				(width 0.1524)
				(type default)
			)
			(layer "F.SilkS")
		)
		(fp_poly
			(pts
				(xy -2.2352 -1.001014) (xy -1.533144 -0.649986) (xy -2.2352 -0.298958)
			)
			(stroke
				(width 0)
				(type default)
			)
			(fill yes)
			(layer "F.SilkS")
		)
		(fp_line
			(start -0.674878 -1.100074)
			(end 0.674878 -1.100074)
			(stroke
				(width 0.1)
				(type default)
			)
			(layer "F.Fab")
		)
		(fp_line
			(start -0.674878 1.100074)
			(end -0.674878 -1.100074)
			(stroke
				(width 0.1)
				(type default)
			)
			(layer "F.Fab")
		)
		(fp_line
			(start 0.674878 -1.100074)
			(end 0.674878 1.100074)
			(stroke
				(width 0.1)
				(type default)
			)
			(layer "F.Fab")
		)
		(fp_line
			(start 0.674878 1.100074)
			(end -0.674878 1.100074)
			(stroke
				(width 0.1)
				(type default)
			)
			(layer "F.Fab")
		)
		(fp_poly
			(pts
				(xy -2.2352 -0.298958) (xy -2.2352 -1.001014) (xy -1.533144 -0.649986)
			)
			(stroke
				(width 0)
				(type default)
			)
			(fill yes)
			(layer "F.Fab")
		)
		(pad "1" smd rect
			(at -0.94996 -0.649986 90)
			(size 0.4318 0.508)
			(layers "F.Cu" "F.Mask" "F.Paste")
			(net "GND")
		)
		(pad "2" smd rect
			(at -0.94996 0 90)
			(size 0.4318 0.508)
			(layers "F.Cu" "F.Mask" "F.Paste")
			(net "GPU_3V3IO_RSVD3")
		)
		(pad "3" smd rect
			(at -0.94996 0.649986 90)
			(size 0.4318 0.508)
			(layers "F.Cu" "F.Mask" "F.Paste")
			(net "GPU_3V3IO_RSVD3_ISO")
		)
		(pad "4" smd rect
			(at 0.94996 0.649986 90)
			(size 0.4318 0.508)
			(layers "F.Cu" "F.Mask" "F.Paste")
			(net "GND")
		)
		(pad "5" smd rect
			(at 0.94996 0 90)
			(size 0.4318 0.508)
			(layers "F.Cu" "F.Mask" "F.Paste")
			(net "GPU_3V3IO_RSVD3_N")
		)
		(pad "6" smd rect
			(at 0.94996 -0.649986 90)
			(size 0.4318 0.508)
			(layers "F.Cu" "F.Mask" "F.Paste")
			(net "GPU_3V3IO_RSVD3_N")
		)
	)
	(footprint ""
		(layer "F.Cu")
		(at 16.422878 -16.099536 90)
		(property "Reference" "C806"
			(at 0 0 90)
			(layer "F.SilkS")
			(hide yes)
			(effects
				(font
					(size 1.27 1.27)
				)
			)
		)
		(property "Value" ""
			(at 0 0 90)
			(layer "F.Fab")
			(effects
				(font
					(size 1.27 1.27)
				)
			)
		)
		(duplicate_pad_numbers_are_jumpers no)
		(fp_line
			(start 0.299974 -0.150114)
			(end 0.299974 0.150114)
			(stroke
				(width 0.1)
				(type default)
			)
			(layer "F.Fab")
		)
		(fp_line
			(start -0.299974 -0.150114)
			(end 0.299974 -0.150114)
			(stroke
				(width 0.1)
				(type default)
			)
			(layer "F.Fab")
		)
		(fp_line
			(start 0.299974 0.150114)
			(end -0.299974 0.150114)
			(stroke
				(width 0.1)
				(type default)
			)
			(layer "F.Fab")
		)
		(fp_line
			(start -0.299974 0.150114)
			(end -0.299974 -0.150114)
			(stroke
				(width 0.1)
				(type default)
			)
			(layer "F.Fab")
		)
		(pad "1" smd rect
			(at -0.2667 0 90)
			(size 0.3048 0.381)
			(layers "F.Cu" "F.Mask" "F.Paste")
			(net "P5E_CPU1_PE1_TX_C_DN<15>")
		)
		(pad "2" smd rect
			(at 0.2667 0 90)
			(size 0.3048 0.381)
			(layers "F.Cu" "F.Mask" "F.Paste")
			(net "P5E_CPU1_PE1_TX_DN<15>")
		)
	)
	(footprint ""
		(layer "F.Cu")
		(at 40.506396 -337.471258)
		(property "Reference" "PC414"
			(at 0 0 0)
			(layer "F.SilkS")
			(hide yes)
			(effects
				(font
					(size 1.27 1.27)
				)
			)
		)
		(property "Value" ""
			(at 0 0 0)
			(layer "F.Fab")
			(effects
				(font
					(size 1.27 1.27)
				)
			)
		)
		(duplicate_pad_numbers_are_jumpers no)
		(fp_line
			(start 2.750058 0.999998)
			(end -2.750058 0.999998)
			(stroke
				(width 0.1524)
				(type default)
			)
			(layer "F.SilkS")
		)
		(fp_circle
			(center 0 0.999998)
			(end 2.750058 0.999998)
			(stroke
				(width 0.1524)
				(type default)
			)
			(fill no)
			(layer "F.SilkS")
		)
		(fp_poly
			(pts
				(arc
					(start 2.750058 0.999998)
					(mid 0 3.750056)
					(end -2.750058 0.999998)
				)
			)
			(stroke
				(width 0)
				(type default)
			)
			(fill yes)
			(layer "F.SilkS")
		)
		(fp_circle
			(center 0 0.999998)
			(end 2.750058 0.999998)
			(stroke
				(width 0.1)
				(type default)
			)
			(fill no)
			(layer "F.Fab")
		)
		(pad "1" thru_hole rect
			(at 0 0)
			(size 1.5748 1.5748)
			(drill 1.0668)
			(layers "*.Cu" "*.Mask")
			(remove_unused_layers no)
			(net "PVCCFA_EHV_FIVRA_CPU1")
			(clearance 0)
			(padstack
				(mode front_inner_back)
				(layer "Inner"
					(shape circle)
					(size 1.5748 1.5748)
					(clearance 0)
				)
				(layer "B.Cu"
					(shape rect)
					(size 1.5748 1.5748)
					(clearance 0)
				)
			)
		)
		(pad "2" thru_hole circle
			(at 0 1.999996)
			(size 1.5748 1.5748)
			(drill 1.0668)
			(layers "*.Cu" "*.Mask")
			(remove_unused_layers no)
			(net "GND")
			(clearance 0)
		)
	)
)
